(kicad_pcb
	(version 20221018)
	(generator pcbnew)
	(general
    (thickness 1.7403)
  )
	(paper "A4")
	(title_block
    (title "Data Center RDIMM DDR4 Tester")
    (date "2024-09-30")
    (rev "1.2.4")
		(comment 9 "footprints 137-142 of 690")
	)
	(layers
    (0 "F.Cu" signal)
    (1 "In1.Cu" power)
    (2 "In2.Cu" signal)
    (3 "In3.Cu" power)
    (4 "In4.Cu" power)
    (5 "In5.Cu" signal)
    (6 "In6.Cu" power)
    (7 "In7.Cu" signal)
    (8 "In8.Cu" power)
    (9 "In9.Cu" signal)
    (10 "In10.Cu" power)
    (31 "B.Cu" signal)
    (32 "B.Adhes" user "B.Adhesive")
    (33 "F.Adhes" user "F.Adhesive")
    (34 "B.Paste" user)
    (35 "F.Paste" user)
    (36 "B.SilkS" user "B.Silkscreen")
    (37 "F.SilkS" user "F.Silkscreen")
    (38 "B.Mask" user)
    (39 "F.Mask" user)
    (40 "Dwgs.User" user "User.Drawings")
    (41 "Cmts.User" user "User.Comments")
    (42 "Eco1.User" user "User.Eco1")
    (43 "Eco2.User" user "User.Eco2")
    (44 "Edge.Cuts" user)
    (45 "Margin" user)
    (46 "B.CrtYd" user "B.Courtyard")
    (47 "F.CrtYd" user "F.Courtyard")
    (48 "B.Fab" user)
    (49 "F.Fab" user)
  )
	(footprint "data-center-rdimm-ddr4-tester-footprints:USON-14_3.5X1.3X0.5mm_P0.5mm" (layer "F.Cu")
    (at 229.37 80.45 90)
    (property "Author" "Antmicro")
    (property "DNP" "DNP")
    (property "License" "Apache-2.0")
    (property "MPN" "TPD6E05U06RVZR")
    (property "Manufacturer" "Texas Instruments")
    (property "Sheetfile" "config-spi.kicad_sch")
    (property "Sheetname" "Config SPI flash")
    (property "dnp" "")
    (property "exclude_from_bom" "")
    (attr exclude_from_pos_files exclude_from_bom)
    (fp_text reference "D4" (at -2.97 -0.77) (layer "F.SilkS")
        (effects (font (size 0.7 0.7) (thickness 0.15)) (justify left bottom))
    )
    (fp_text value "TPD6E05U06RVZR" (at 0 2.2 90) (layer "F.Fab") hide
        (effects (font (size 0.7 0.7) (thickness 0.15)) (justify left bottom))
    )
    (fp_text user "${REFERENCE}" (at -1.851 4.498 90) (layer "F.Fab") hide
        (effects (font (size 0.7 0.7) (thickness 0.15)) (justify left bottom))
    )
    (fp_text user "License: Apache-2.0" (at -1.851 6.9 90) (layer "F.Fab") hide
        (effects (font (size 0.7 0.7) (thickness 0.15)) (justify left bottom))
    )
    (fp_text user "Author: Antmicro" (at -1.851 5.7 90) (layer "F.Fab") hide
        (effects (font (size 0.7 0.7) (thickness 0.15)) (justify left bottom))
    )
    (fp_line (start -1.86 -0.96) (end 1.85 -0.96)
      (stroke (width 0.15) (type solid)) (layer "F.SilkS"))
    (fp_line (start -1.86 0.69) (end -1.86 -0.96)
      (stroke (width 0.15) (type solid)) (layer "F.SilkS"))
    (fp_line (start -1.59 0.96) (end -1.86 0.69)
      (stroke (width 0.15) (type solid)) (layer "F.SilkS"))
    (fp_line (start 1.85 -0.96) (end 1.85 0.96)
      (stroke (width 0.15) (type solid)) (layer "F.SilkS"))
    (fp_line (start 1.85 0.96) (end -1.59 0.96)
      (stroke (width 0.15) (type solid)) (layer "F.SilkS"))
    (fp_circle (center -1.86 0.98) (end -1.81 0.98)
      (stroke (width 0.15) (type solid)) (fill none) (layer "F.SilkS"))
    (fp_rect (start -2 -1.125) (end 2 1.125)
      (stroke (width 0.05) (type solid)) (fill none) (layer "F.CrtYd"))
    (fp_line (start -1.86 -0.96) (end -1.86 0.69)
      (stroke (width 0.15) (type solid)) (layer "F.Fab"))
    (fp_line (start -1.845 0.705) (end -1.595 0.955)
      (stroke (width 0.15) (type solid)) (layer "F.Fab"))
    (fp_line (start -1.58 0.96) (end 1.85 0.96)
      (stroke (width 0.15) (type solid)) (layer "F.Fab"))
    (fp_line (start 1.85 -0.96) (end -1.86 -0.96)
      (stroke (width 0.15) (type solid)) (layer "F.Fab"))
    (fp_line (start 1.85 0.96) (end 1.85 -0.96)
      (stroke (width 0.15) (type solid)) (layer "F.Fab"))
    (pad "1" smd roundrect (at -1.5 0.623 90) (size 0.2 0.5) (layers "F.Cu" "F.Paste" "F.Mask") (roundrect_rratio 0.25)
      (net 13 "TMS_JTAG") (pinfunction "D1+") (pintype "passive"))
    (pad "2" smd roundrect (at -1 0.623 90) (size 0.2 0.5) (layers "F.Cu" "F.Paste" "F.Mask") (roundrect_rratio 0.25)
      (net 12 "TCK_JTAG") (pinfunction "D1-") (pintype "passive"))
    (pad "3" smd roundrect (at -0.5 0.623 90) (size 0.2 0.5) (layers "F.Cu" "F.Paste" "F.Mask") (roundrect_rratio 0.25)
      (net 97 "unconnected-(D4-D2+-Pad12)") (pinfunction "D2+") (pintype "passive+no_connect"))
    (pad "4" smd roundrect (at 0 0.623 90) (size 0.2 0.5) (layers "F.Cu" "F.Paste" "F.Mask") (roundrect_rratio 0.25)
      (net 98 "unconnected-(D4-D2--Pad11)") (pinfunction "D2-") (pintype "passive+no_connect"))
    (pad "5" smd roundrect (at 0.498 0.623 90) (size 0.2 0.5) (layers "F.Cu" "F.Paste" "F.Mask") (roundrect_rratio 0.25)
      (net 9 "GND") (pinfunction "GND") (pintype "power_in"))
    (pad "6" smd roundrect (at 0.998 0.623 90) (size 0.2 0.5) (layers "F.Cu" "F.Paste" "F.Mask") (roundrect_rratio 0.25)
      (net 15 "TDO_JTAG") (pinfunction "D3+") (pintype "passive"))
    (pad "7" smd roundrect (at 1.499 0.623 90) (size 0.2 0.5) (layers "F.Cu" "F.Paste" "F.Mask") (roundrect_rratio 0.25)
      (net 14 "TDI_JTAG") (pinfunction "D3-") (pintype "passive"))
    (pad "8" smd roundrect (at 1.499 -0.625 90) (size 0.2 0.5) (layers "F.Cu" "F.Paste" "F.Mask") (roundrect_rratio 0.25)
      (net 14 "TDI_JTAG") (pinfunction "D3-") (pintype "passive"))
    (pad "9" smd roundrect (at 0.998 -0.625 90) (size 0.2 0.5) (layers "F.Cu" "F.Paste" "F.Mask") (roundrect_rratio 0.25)
      (net 15 "TDO_JTAG") (pinfunction "D3+") (pintype "passive"))
    (pad "10" smd roundrect (at 0.498 -0.625 90) (size 0.2 0.5) (layers "F.Cu" "F.Paste" "F.Mask") (roundrect_rratio 0.25)
      (net 9 "GND") (pinfunction "GND") (pintype "passive"))
    (pad "11" smd roundrect (at 0 -0.625 90) (size 0.2 0.5) (layers "F.Cu" "F.Paste" "F.Mask") (roundrect_rratio 0.25)
      (net 98 "unconnected-(D4-D2--Pad11)") (pinfunction "D2-") (pintype "passive+no_connect"))
    (pad "12" smd roundrect (at -0.5 -0.625 90) (size 0.2 0.5) (layers "F.Cu" "F.Paste" "F.Mask") (roundrect_rratio 0.25)
      (net 97 "unconnected-(D4-D2+-Pad12)") (pinfunction "D2+") (pintype "passive+no_connect"))
    (pad "13" smd roundrect (at -1 -0.625 90) (size 0.2 0.5) (layers "F.Cu" "F.Paste" "F.Mask") (roundrect_rratio 0.25)
      (net 12 "TCK_JTAG") (pinfunction "D1-") (pintype "passive"))
    (pad "14" smd roundrect (at -1.5 -0.625 90) (size 0.2 0.5) (layers "F.Cu" "F.Paste" "F.Mask") (roundrect_rratio 0.25)
      (net 13 "TMS_JTAG") (pinfunction "D1+") (pintype "passive"))
  )
	(footprint "data-center-rdimm-ddr4-tester-footprints:LED_0603_1608Metric_G" (layer "F.Cu")
    (at 243.15 128.9 -90)
    (descr "LED SMD 0603 Green")
    (tags "LED SMD 0603 Green")
    (property "Author" "Antmicro")
    (property "License" "Apache-2.0")
    (property "MPN" "KP-1608CGCK")
    (property "Manufacturer" "Kingbright")
    (property "Sheetfile" "config-spi.kicad_sch")
    (property "Sheetname" "Config SPI flash")
    (attr smd)
    (fp_text reference "D1" (at 2.02 -2.42 -90) (layer "F.SilkS")
        (effects (font (size 0.7 0.7) (thickness 0.15)) (justify left bottom))
    )
    (fp_text value "LED_G_0603_KP-1608CGCK" (at 0 1.6 -90) (layer "F.Fab") hide
        (effects (font (size 0.7 0.7) (thickness 0.15)) (justify left bottom))
    )
    (fp_text user "License: Apache-2.0" (at -1.31 5.769 -90) (layer "F.Fab") hide
        (effects (font (size 0.7 0.7) (thickness 0.15)) (justify left bottom))
    )
    (fp_text user "Author: Antmicro" (at -1.31 4.769 -90) (layer "F.Fab") hide
        (effects (font (size 0.7 0.7) (thickness 0.15)) (justify left bottom))
    )
    (fp_text user "${REFERENCE}" (at -1.31 3.769 -90) (layer "F.Fab") hide
        (effects (font (size 0.7 0.7) (thickness 0.15)) (justify left bottom))
    )
    (fp_line (start -0.27 -0.35) (end 0.27 -0.35)
      (stroke (width 0.15) (type solid)) (layer "F.SilkS"))
    (fp_line (start -0.27 0.351) (end 0.27 0.351)
      (stroke (width 0.15) (type solid)) (layer "F.SilkS"))
    (fp_line (start -0.106328 -0.200008) (end -0.106328 0.199992)
      (stroke (width 0.1) (type solid)) (layer "F.SilkS"))
    (fp_line (start -0.106328 -0.200008) (end 0.093672 -0.000008)
      (stroke (width 0.1) (type solid)) (layer "F.SilkS"))
    (fp_line (start -0.106328 -0.000008) (end -0.29 0)
      (stroke (width 0.1) (type solid)) (layer "F.SilkS"))
    (fp_line (start 0.093672 -0.200008) (end 0.093672 0.199992)
      (stroke (width 0.1) (type solid)) (layer "F.SilkS"))
    (fp_line (start 0.093672 -0.000008) (end -0.106328 0.199992)
      (stroke (width 0.1) (type solid)) (layer "F.SilkS"))
    (fp_line (start 0.093672 -0.000008) (end 0.293672 -0.000008)
      (stroke (width 0.1) (type solid)) (layer "F.SilkS"))
    (fp_line (start 1.25 0.32) (end 1.25 -0.32)
      (stroke (width 0.15) (type solid)) (layer "F.SilkS"))
    (fp_rect (start 1.26 0.65) (end -1.26 -0.65)
      (stroke (width 0.05) (type solid)) (fill none) (layer "F.CrtYd"))
    (fp_line (start -0.599 0) (end -0.201 0)
      (stroke (width 0.15) (type solid)) (layer "F.Fab"))
    (fp_line (start -0.201 -0.2) (end -0.201 0)
      (stroke (width 0.15) (type solid)) (layer "F.Fab"))
    (fp_line (start -0.201 0) (end -0.201 0.202)
      (stroke (width 0.15) (type solid)) (layer "F.Fab"))
    (fp_line (start -0.201 0.202) (end 0.101 0)
      (stroke (width 0.15) (type solid)) (layer "F.Fab"))
    (fp_line (start 0.101 0) (end -0.201 -0.2)
      (stroke (width 0.15) (type solid)) (layer "F.Fab"))
    (fp_line (start 0.199 -0.2) (end 0.199 -0.1)
      (stroke (width 0.15) (type solid)) (layer "F.Fab"))
    (fp_line (start 0.199 0) (end 0.597 0)
      (stroke (width 0.15) (type solid)) (layer "F.Fab"))
    (fp_line (start 0.199 0.202) (end 0.199 -0.1)
      (stroke (width 0.15) (type solid)) (layer "F.Fab"))
    (fp_rect (start -0.848 -0.4) (end 0.85 0.402)
      (stroke (width 0.15) (type solid)) (fill none) (layer "F.Fab"))
    (pad "1" smd rect (at -0.75 0 90) (size 0.8 0.8) (layers "F.Cu" "F.Paste" "F.Mask")
      (net 143 "3V3_SYS") (pinfunction "1") (pintype "passive"))
    (pad "2" smd rect (at 0.75 0 90) (size 0.8 0.8) (layers "F.Cu" "F.Paste" "F.Mask")
      (net 89 "Net-(D1-Pad2)") (pinfunction "2") (pintype "passive"))
  )
	(footprint "data-center-rdimm-ddr4-tester-footprints:LED_0603_1608Metric_G" (layer "F.Cu")
    (at 243.15 131.44 -90)
    (descr "LED SMD 0603 Green")
    (tags "LED SMD 0603 Green")
    (property "Author" "Antmicro")
    (property "License" "Apache-2.0")
    (property "MPN" "KP-1608CGCK")
    (property "Manufacturer" "Kingbright")
    (property "Sheetfile" "config-spi.kicad_sch")
    (property "Sheetname" "Config SPI flash")
    (attr smd)
    (fp_text reference "D10" (at 1.58 -2.42 -90) (layer "F.SilkS")
        (effects (font (size 0.7 0.7) (thickness 0.15)) (justify left bottom))
    )
    (fp_text value "LED_G_0603_KP-1608CGCK" (at 0 1.6 -90) (layer "F.Fab") hide
        (effects (font (size 0.7 0.7) (thickness 0.15)) (justify left bottom))
    )
    (fp_text user "${REFERENCE}" (at -1.31 3.769 -90) (layer "F.Fab") hide
        (effects (font (size 0.7 0.7) (thickness 0.15)) (justify left bottom))
    )
    (fp_text user "Author: Antmicro" (at -1.31 4.769 -90) (layer "F.Fab") hide
        (effects (font (size 0.7 0.7) (thickness 0.15)) (justify left bottom))
    )
    (fp_text user "License: Apache-2.0" (at -1.31 5.769 -90) (layer "F.Fab") hide
        (effects (font (size 0.7 0.7) (thickness 0.15)) (justify left bottom))
    )
    (fp_line (start -0.27 -0.35) (end 0.27 -0.35)
      (stroke (width 0.15) (type solid)) (layer "F.SilkS"))
    (fp_line (start -0.27 0.351) (end 0.27 0.351)
      (stroke (width 0.15) (type solid)) (layer "F.SilkS"))
    (fp_line (start -0.106328 -0.200008) (end -0.106328 0.199992)
      (stroke (width 0.1) (type solid)) (layer "F.SilkS"))
    (fp_line (start -0.106328 -0.200008) (end 0.093672 -0.000008)
      (stroke (width 0.1) (type solid)) (layer "F.SilkS"))
    (fp_line (start -0.106328 -0.000008) (end -0.29 0)
      (stroke (width 0.1) (type solid)) (layer "F.SilkS"))
    (fp_line (start 0.093672 -0.200008) (end 0.093672 0.199992)
      (stroke (width 0.1) (type solid)) (layer "F.SilkS"))
    (fp_line (start 0.093672 -0.000008) (end -0.106328 0.199992)
      (stroke (width 0.1) (type solid)) (layer "F.SilkS"))
    (fp_line (start 0.093672 -0.000008) (end 0.293672 -0.000008)
      (stroke (width 0.1) (type solid)) (layer "F.SilkS"))
    (fp_line (start 1.25 0.32) (end 1.25 -0.32)
      (stroke (width 0.15) (type solid)) (layer "F.SilkS"))
    (fp_rect (start 1.26 0.65) (end -1.26 -0.65)
      (stroke (width 0.05) (type solid)) (fill none) (layer "F.CrtYd"))
    (fp_line (start -0.599 0) (end -0.201 0)
      (stroke (width 0.15) (type solid)) (layer "F.Fab"))
    (fp_line (start -0.201 -0.2) (end -0.201 0)
      (stroke (width 0.15) (type solid)) (layer "F.Fab"))
    (fp_line (start -0.201 0) (end -0.201 0.202)
      (stroke (width 0.15) (type solid)) (layer "F.Fab"))
    (fp_line (start -0.201 0.202) (end 0.101 0)
      (stroke (width 0.15) (type solid)) (layer "F.Fab"))
    (fp_line (start 0.101 0) (end -0.201 -0.2)
      (stroke (width 0.15) (type solid)) (layer "F.Fab"))
    (fp_line (start 0.199 -0.2) (end 0.199 -0.1)
      (stroke (width 0.15) (type solid)) (layer "F.Fab"))
    (fp_line (start 0.199 0) (end 0.597 0)
      (stroke (width 0.15) (type solid)) (layer "F.Fab"))
    (fp_line (start 0.199 0.202) (end 0.199 -0.1)
      (stroke (width 0.15) (type solid)) (layer "F.Fab"))
    (fp_rect (start -0.848 -0.4) (end 0.85 0.402)
      (stroke (width 0.15) (type solid)) (fill none) (layer "F.Fab"))
    (pad "1" smd rect (at -0.75 0 90) (size 0.8 0.8) (layers "F.Cu" "F.Paste" "F.Mask")
      (net 143 "3V3_SYS") (pinfunction "1") (pintype "passive"))
    (pad "2" smd rect (at 0.75 0 90) (size 0.8 0.8) (layers "F.Cu" "F.Paste" "F.Mask")
      (net 90 "Net-(D10-Pad2)") (pinfunction "2") (pintype "passive"))
  )
	(footprint "data-center-rdimm-ddr4-tester-footprints:R_0402_1005Metric" (layer "F.Cu")
    (at 220.15 86.75)
    (descr "Resistor SMD 0402")
    (tags "resistor SMD 0402")
    (property "Author" "Antmicro")
    (property "Current" "1A")
    (property "License" "Apache-2.0")
    (property "MPN" "ERJ2GE0R00X")
    (property "Manufacturer" "Panasonic")
    (property "Sheetfile" "config-spi.kicad_sch")
    (property "Sheetname" "Config SPI flash")
    (property "Tolerance" "")
    (property "Val" "0R")
    (property "ki_description" "0R resistor in 0402 package with unspecified tolerance")
    (attr smd)
    (fp_text reference "R9" (at -1.14 2.49) (layer "F.SilkS")
        (effects (font (size 0.7 0.7) (thickness 0.15)) (justify left bottom))
    )
    (fp_text value "R_0R_0402" (at 0 1.4) (layer "F.Fab") hide
        (effects (font (size 0.7 0.7) (thickness 0.15)) (justify left bottom))
    )
    (fp_text user "${REFERENCE}" (at -0.95 3.168) (layer "F.Fab") hide
        (effects (font (size 0.7 0.7) (thickness 0.15)) (justify left bottom))
    )
    (fp_text user "License: Apache-2.0" (at -0.95 5.169) (layer "F.Fab") hide
        (effects (font (size 0.7 0.7) (thickness 0.15)) (justify left bottom))
    )
    (fp_text user "Author: Antmicro" (at -0.95 4.169) (layer "F.Fab") hide
        (effects (font (size 0.7 0.7) (thickness 0.15)) (justify left bottom))
    )
    (fp_rect (start -0.93 -0.47) (end 0.93 0.47)
      (stroke (width 0.05) (type solid)) (fill none) (layer "F.CrtYd"))
    (fp_rect (start -0.5 -0.25) (end 0.5 0.25)
      (stroke (width 0.15) (type solid)) (fill none) (layer "F.Fab"))
    (pad "1" smd roundrect (at -0.485 0) (size 0.59 0.64) (layers "F.Cu" "F.Paste" "F.Mask") (roundrect_rratio 0.25)
      (net 23 "MODE0") (pintype "passive"))
    (pad "2" smd roundrect (at 0.485 0) (size 0.59 0.64) (layers "F.Cu" "F.Paste" "F.Mask") (roundrect_rratio 0.25)
      (net 143 "3V3_SYS") (pintype "passive"))
  )
	(footprint "data-center-rdimm-ddr4-tester-footprints:R_0402_1005Metric" (layer "F.Cu")
    (at 220.135 87.85)
    (descr "Resistor SMD 0402")
    (tags "resistor SMD 0402")
    (property "Author" "Antmicro")
    (property "Current" "1A")
    (property "DNP" "DNP")
    (property "License" "Apache-2.0")
    (property "MPN" "ERJ2GE0R00X")
    (property "Manufacturer" "Panasonic")
    (property "Sheetfile" "config-spi.kicad_sch")
    (property "Sheetname" "Config SPI flash")
    (property "Tolerance" "")
    (property "Val" "0R")
    (property "dnp" "")
    (property "exclude_from_bom" "")
    (property "ki_description" "0R resistor in 0402 package with unspecified tolerance")
    (attr exclude_from_pos_files exclude_from_bom)
    (fp_text reference "R11" (at -1.14 2.49) (layer "F.SilkS")
        (effects (font (size 0.7 0.7) (thickness 0.15)) (justify left bottom))
    )
    (fp_text value "R_0R_0402" (at 0 1.4) (layer "F.Fab") hide
        (effects (font (size 0.7 0.7) (thickness 0.15)) (justify left bottom))
    )
    (fp_text user "Author: Antmicro" (at -0.95 4.169) (layer "F.Fab") hide
        (effects (font (size 0.7 0.7) (thickness 0.15)) (justify left bottom))
    )
    (fp_text user "${REFERENCE}" (at -0.95 3.168) (layer "F.Fab") hide
        (effects (font (size 0.7 0.7) (thickness 0.15)) (justify left bottom))
    )
    (fp_text user "License: Apache-2.0" (at -0.95 5.169) (layer "F.Fab") hide
        (effects (font (size 0.7 0.7) (thickness 0.15)) (justify left bottom))
    )
    (fp_rect (start -0.93 -0.47) (end 0.93 0.47)
      (stroke (width 0.05) (type solid)) (fill none) (layer "F.CrtYd"))
    (fp_rect (start -0.5 -0.25) (end 0.5 0.25)
      (stroke (width 0.15) (type solid)) (fill none) (layer "F.Fab"))
    (pad "1" smd roundrect (at -0.485 0) (size 0.59 0.64) (layers "F.Cu" "F.Paste" "F.Mask") (roundrect_rratio 0.25)
      (net 23 "MODE0") (pintype "passive"))
    (pad "2" smd roundrect (at 0.485 0) (size 0.59 0.64) (layers "F.Cu" "F.Paste" "F.Mask") (roundrect_rratio 0.25)
      (net 9 "GND") (pintype "passive"))
  )
	(footprint "data-center-rdimm-ddr4-tester-footprints:R_0402_1005Metric" (layer "F.Cu")
    (at 222.225 86.75)
    (descr "Resistor SMD 0402")
    (tags "resistor SMD 0402")
    (property "Author" "Antmicro")
    (property "Current" "1A")
    (property "DNP" "DNP")
    (property "License" "Apache-2.0")
    (property "MPN" "ERJ2GE0R00X")
    (property "Manufacturer" "Panasonic")
    (property "Sheetfile" "config-spi.kicad_sch")
    (property "Sheetname" "Config SPI flash")
    (property "Tolerance" "")
    (property "Val" "0R")
    (property "dnp" "")
    (property "exclude_from_bom" "")
    (property "ki_description" "0R resistor in 0402 package with unspecified tolerance")
    (attr exclude_from_pos_files exclude_from_bom)
    (fp_text reference "R12" (at -1.135 2.51) (layer "F.SilkS")
        (effects (font (size 0.7 0.7) (thickness 0.15)) (justify left bottom))
    )
    (fp_text value "R_0R_0402" (at 0 1.4) (layer "F.Fab") hide
        (effects (font (size 0.7 0.7) (thickness 0.15)) (justify left bottom))
    )
    (fp_text user "License: Apache-2.0" (at -0.95 5.169) (layer "F.Fab") hide
        (effects (font (size 0.7 0.7) (thickness 0.15)) (justify left bottom))
    )
    (fp_text user "${REFERENCE}" (at -0.95 3.168) (layer "F.Fab") hide
        (effects (font (size 0.7 0.7) (thickness 0.15)) (justify left bottom))
    )
    (fp_text user "Author: Antmicro" (at -0.95 4.169) (layer "F.Fab") hide
        (effects (font (size 0.7 0.7) (thickness 0.15)) (justify left bottom))
    )
    (fp_rect (start -0.93 -0.47) (end 0.93 0.47)
      (stroke (width 0.05) (type solid)) (fill none) (layer "F.CrtYd"))
    (fp_rect (start -0.5 -0.25) (end 0.5 0.25)
      (stroke (width 0.15) (type solid)) (fill none) (layer "F.Fab"))
    (pad "1" smd roundrect (at -0.485 0) (size 0.59 0.64) (layers "F.Cu" "F.Paste" "F.Mask") (roundrect_rratio 0.25)
      (net 24 "MODE1") (pintype "passive"))
    (pad "2" smd roundrect (at 0.485 0) (size 0.59 0.64) (layers "F.Cu" "F.Paste" "F.Mask") (roundrect_rratio 0.25)
      (net 143 "3V3_SYS") (pintype "passive"))
  )
)
